# S9S_MB_2U (Grand Teton) — schematic netlist excerpt (pin names and nets, part order shuffled) for the footprints in the layout excerpt that follows; sources: Cadence DE-HDL packaged netlist, KiCad conversion of 03242023_DA0F0TMBIJ0_F0T_Motherboard_J_brd_V01_OCP.brd

PU8_P0_6  ISL99390FRZTR5935  ISL99390FRZ-TR5935 IC  pkg QFN21_6X5XB  page 269
  VOS  = PVCCIN_CPU0_VOS6
  AGND  = GND
  VCC  = PVCCIN_CPU0_VDD6
  PVCC  = PVCCIN_CPU0_PVCC
  PGND1  = GND
  GL1  = NC
  PGND2  = GND
  SW  = SW_PVCCIN_CPU0_SW6
  VIN1  = SW_P12V_PVCCIN_CPU0_FLT
  VIN2  = SW_P12V_PVCCIN_CPU0_FLT
  DNC  = NC
  PHASE  = SW_PVCCIN_CPU0_BOOTR6
  BOOT  = SW_PVCCIN_CPU0_BOOT6
  PWM  = PVCCIN_CPU0_PWM6
  EN  = PVCCIN_CPU0_VDD6
  TOUT_FLT  = PVCCIN_CPU0_ATSEN
  LSET  = PVCCIN_CPU0_LSET6
  IOUT  = PVCCIN_CPU0_IMON6
  REFIN  = PVCCIN_CPU0_VREF
  PGND3  = GND
  GL2  = NC

(kicad_pcb
	(version 20260206)
	(generator "pcbnew")
	(generator_version "10.0")
	(general
		(thickness 1.6)
		(legacy_teardrops no)
	)
	(paper "A4")
	(title_block
		(title "03242023_DA0F0TMBIJ0_F0T_Motherboard_J_brd_V01_OCP.brd")
		(comment 1 "Grand Teton / footprints 378-378 of 6105")
	)
	(layers
		(0 "F.Cu" signal "TOP")
		(4 "In1.Cu" signal "GND")
		(6 "In2.Cu" signal "IN1")
		(8 "In3.Cu" signal "GND1")
		(10 "In4.Cu" signal "IN2")
		(12 "In5.Cu" signal "GND2")
		(14 "In6.Cu" signal "IN3")
		(16 "In7.Cu" signal "GND3")
		(18 "In8.Cu" signal "VCC")
		(20 "In9.Cu" signal "VCC1")
		(22 "In10.Cu" signal "GND4")
		(24 "In11.Cu" signal "IN4")
		(26 "In12.Cu" signal "GND5")
		(28 "In13.Cu" signal "IN5")
		(30 "In14.Cu" signal "GND6")
		(32 "In15.Cu" signal "IN6")
		(34 "In16.Cu" signal "GND7")
		(2 "B.Cu" signal "BOTTOM")
		(9 "F.Adhes" user "F.Adhesive")
		(11 "B.Adhes" user "B.Adhesive")
		(13 "F.Paste" user "Package Geometry/Pastemask Top")
		(15 "B.Paste" user "Package Geometry/Pastemask Bottom")
		(5 "F.SilkS" user "Ref Des/Silkscreen Top")
		(7 "B.SilkS" user "Ref Des/Silkscreen Bottom")
		(1 "F.Mask" user "Board Geometry/Soldermask Top")
		(3 "B.Mask" user "Board Geometry/Soldermask Bottom")
		(17 "Dwgs.User" user "User.Drawings")
		(19 "Cmts.User" user "User.Comments")
		(21 "Eco1.User" user "User.Eco1")
		(23 "Eco2.User" user "User.Eco2")
		(25 "Edge.Cuts" user "Board Geometry/Outline")
		(27 "Margin" user)
		(31 "F.CrtYd" user "Package Geometry/Place Bound Top")
		(29 "B.CrtYd" user "Package Geometry/Place Bound Bottom")
		(35 "F.Fab" user "Ref Des/Assembly Top")
		(33 "B.Fab" user "Ref Des/Assembly Bottom")
	)
	(footprint ""
		(layer "F.Cu")
		(at 336.777076 -337.126326)
		(property "Reference" "PU8_P0_6"
			(at -1.222756 -6.773672 0)
			(unlocked yes)
			(layer "F.SilkS")
			(effects
				(font
					(size 0.7874 0.5842)
					(thickness 0.1524)
				)
				(justify left)
			)
		)
		(property "Value" ""
			(at 0 0 0)
			(layer "F.Fab")
			(effects
				(font
					(size 1.27 1.27)
				)
			)
		)
		(duplicate_pad_numbers_are_jumpers no)
		(fp_line
			(start -2.500122 -2.999994)
			(end -2.24409 -2.999994)
			(stroke
				(width 0.1524)
				(type default)
			)
			(layer "F.SilkS")
		)
		(fp_line
			(start -2.500122 -2.529078)
			(end -2.500122 -2.999994)
			(stroke
				(width 0.1524)
				(type default)
			)
			(layer "F.SilkS")
		)
		(fp_line
			(start -2.500122 0.6604)
			(end -2.500122 0.229108)
			(stroke
				(width 0.1524)
				(type default)
			)
			(layer "F.SilkS")
		)
		(fp_line
			(start -2.500122 2.999994)
			(end -2.500122 2.339594)
			(stroke
				(width 0.1524)
				(type default)
			)
			(layer "F.SilkS")
		)
		(fp_line
			(start -2.2987 2.999994)
			(end -2.500122 2.999994)
			(stroke
				(width 0.1524)
				(type default)
			)
			(layer "F.SilkS")
		)
		(fp_line
			(start 2.31394 -2.999994)
			(end 2.500122 -2.999994)
			(stroke
				(width 0.1524)
				(type default)
			)
			(layer "F.SilkS")
		)
		(fp_line
			(start 2.500122 -2.999994)
			(end 2.500122 -2.44348)
			(stroke
				(width 0.1524)
				(type default)
			)
			(layer "F.SilkS")
		)
		(fp_line
			(start 2.500122 2.339594)
			(end 2.500122 2.999994)
			(stroke
				(width 0.1524)
				(type default)
			)
			(layer "F.SilkS")
		)
		(fp_line
			(start 2.500122 2.999994)
			(end 2.2987 2.999994)
			(stroke
				(width 0.1524)
				(type default)
			)
			(layer "F.SilkS")
		)
		(fp_poly
			(pts
				(xy -2.21742 -3.606038) (xy -2.72542 -2.590038) (xy -3.23342 -3.606038)
			)
			(stroke
				(width 0)
				(type default)
			)
			(fill yes)
			(layer "F.SilkS")
		)
		(fp_line
			(start -2.500122 -2.999994)
			(end 2.500122 -2.999994)
			(stroke
				(width 0.1)
				(type default)
			)
			(layer "F.Fab")
		)
		(fp_line
			(start -2.500122 2.999994)
			(end -2.500122 -2.999994)
			(stroke
				(width 0.1)
				(type default)
			)
			(layer "F.Fab")
		)
		(fp_line
			(start 2.500122 -2.999994)
			(end 2.500122 2.999994)
			(stroke
				(width 0.1)
				(type default)
			)
			(layer "F.Fab")
		)
		(fp_line
			(start 2.500122 2.999994)
			(end -2.500122 2.999994)
			(stroke
				(width 0.1)
				(type default)
			)
			(layer "F.Fab")
		)
		(fp_poly
			(pts
				(xy -4.218432 -2.783078) (xy -4.218432 -1.767078) (xy -3.202432 -2.275078)
			)
			(stroke
				(width 0)
				(type default)
			)
			(fill yes)
			(layer "F.Fab")
		)
		(pad "1" smd rect
			(at -2.400046 -2.275078 90)
			(size 0.2286 0.6096)
			(layers "F.Cu" "F.Mask" "F.Paste")
			(net "PVCCIN_CPU0_VOS6")
		)
		(pad "2" smd rect
			(at -2.400046 -1.82499 90)
			(size 0.2286 0.6096)
			(layers "F.Cu" "F.Mask" "F.Paste")
			(net "GND")
		)
		(pad "3" smd rect
			(at -2.400046 -1.374902 90)
			(size 0.2286 0.6096)
			(layers "F.Cu" "F.Mask" "F.Paste")
			(net "PVCCIN_CPU0_VDD6")
		)
		(pad "4" smd rect
			(at -2.400046 -0.925068 90)
			(size 0.2286 0.6096)
			(layers "F.Cu" "F.Mask" "F.Paste")
			(net "PVCCIN_CPU0_PVCC")
		)
		(pad "5" smd rect
			(at -2.400046 -0.47498 90)
			(size 0.2286 0.6096)
			(layers "F.Cu" "F.Mask" "F.Paste")
			(net "GND")
		)
		(pad "6" smd rect
			(at -2.400046 -0.024892 90)
			(size 0.2286 0.6096)
			(layers "F.Cu" "F.Mask" "F.Paste")
			(net "Net_8559")
		)
		(pad "7_9-20_24" smd circle
			(at 0 1.150112 90)
			(size 0 0)
			(layers "F.Cu" "F.Mask" "F.Paste")
			(net "GND")
		)
		(pad "10_19" smd rect
			(at 0 2.899918 90)
			(size 0.6096 4.318)
			(layers "F.Cu" "F.Mask" "F.Paste")
			(net "SW_PVCCIN_CPU0_SW6")
		)
		(pad "25_29" smd rect
			(at 1.549908 -1.279906 270)
			(size 2.0574 2.3114)
			(layers "F.Cu" "F.Mask" "F.Paste")
			(net "SW_P12V_PVCCIN_CPU0_FLT")
		)
		(pad "30" smd rect
			(at 2.05994 -2.899918)
			(size 0.2286 0.6096)
			(layers "F.Cu" "F.Mask" "F.Paste")
			(net "SW_P12V_PVCCIN_CPU0_FLT")
		)
		(pad "31" smd rect
			(at 1.610106 -2.899918)
			(size 0.2286 0.6096)
			(layers "F.Cu" "F.Mask" "F.Paste")
			(net "Net_8560")
		)
		(pad "32" smd rect
			(at 1.160018 -2.899918)
			(size 0.2286 0.6096)
			(layers "F.Cu" "F.Mask" "F.Paste")
			(net "SW_PVCCIN_CPU0_BOOTR6")
		)
		(pad "33" smd rect
			(at 0.70993 -2.899918)
			(size 0.2286 0.6096)
			(layers "F.Cu" "F.Mask" "F.Paste")
			(net "SW_PVCCIN_CPU0_BOOT6")
		)
		(pad "34" smd rect
			(at 0.260096 -2.899918)
			(size 0.2286 0.6096)
			(layers "F.Cu" "F.Mask" "F.Paste")
			(net "PVCCIN_CPU0_PWM6")
		)
		(pad "35" smd rect
			(at -0.189992 -2.899918)
			(size 0.2286 0.6096)
			(layers "F.Cu" "F.Mask" "F.Paste")
			(net "PVCCIN_CPU0_VDD6")
		)
		(pad "36" smd rect
			(at -0.64008 -2.899918)
			(size 0.2286 0.6096)
			(layers "F.Cu" "F.Mask" "F.Paste")
			(net "PVCCIN_CPU0_ATSEN")
		)
		(pad "37" smd rect
			(at -1.089914 -2.899918)
			(size 0.2286 0.6096)
			(layers "F.Cu" "F.Mask" "F.Paste")
			(net "PVCCIN_CPU0_LSET6")
		)
		(pad "38" smd rect
			(at -1.540002 -2.899918)
			(size 0.2286 0.6096)
			(layers "F.Cu" "F.Mask" "F.Paste")
			(net "PVCCIN_CPU0_IMON6")
		)
		(pad "39" smd rect
			(at -1.99009 -2.899918)
			(size 0.2286 0.6096)
			(layers "F.Cu" "F.Mask" "F.Paste")
			(net "PVCCIN_CPU0_VREF")
		)
		(pad "40" smd rect
			(at -0.87503 -1.27508)
			(size 1.7526 1.9558)
			(layers "F.Cu" "F.Mask" "F.Paste")
			(net "GND")
		)
		(pad "41" smd rect
			(at -1.525016 0.249936 270)
			(size 0.3048 0.4572)
			(layers "F.Cu" "F.Mask" "F.Paste")
			(net "Net_8558")
		)
		(zone
			(layer "F.Cu")
			(hatch none 0.5)
			(connect_pads
				(clearance 0)
			)
			(min_thickness 0.25)
			(keepout
				(tracks not_allowed)
				(vias allowed)
				(pads allowed)
				(copperpour not_allowed)
				(footprints allowed)
			)
			(placement
				(enabled no)
				(sheetname "")
			)
			(fill
				(thermal_gap 0.5)
				(thermal_bridge_width 0.5)
				(island_removal_mode 0)
			)
			(polygon
				(pts
					(xy 334.974946 -338.816442) (xy 334.974946 -337.764628) (xy 334.73263 -337.764628) (xy 334.73263 -338.844128)
					(xy 334.94726 -338.844128)
				)
			)
		)
		(zone
			(layer "F.Cu")
			(hatch none 0.5)
			(connect_pads
				(clearance 0)
			)
			(min_thickness 0.25)
			(keepout
				(tracks not_allowed)
				(vias allowed)
				(pads allowed)
				(copperpour not_allowed)
				(footprints allowed)
			)
			(placement
				(enabled no)
				(sheetname "")
			)
			(fill
				(thermal_gap 0.5)
				(thermal_bridge_width 0.5)
				(island_removal_mode 0)
			)
			(polygon
				(pts
					(xy 334.276954 -334.126332) (xy 334.276954 -334.875632) (xy 339.277198 -334.875632) (xy 339.277198 -334.126332)
					(xy 338.986876 -334.126332) (xy 338.986876 -334.582008) (xy 334.567276 -334.582008) (xy 334.567276 -334.126332)
				)
			)
		)
	)
)
